# GT_HPDB_BOM_20230321.xlsx — BOM Sharing Template (bom)
| Part Description | Manufacturer | Manufacturing Part Number | Quantity | Location (CRD) | ROOM |
| IC EEPROM(8P) M24256-BRMN6TP(SO8) | SGS-THOMSON(STMicroelectronics) | M24256-BRMN6TP | 1 | U9 |  |
| IC CTRL(48P)ADM1272-1ACPZ-RL(LFCSP_WQ) | ANALOG DEVICES | ADM1272-1ACPZ-RL | 2 | PU7,PU9 | HSC1_BOM2 |
| IC OTHER(8P) LTC4307CMS8#TRPBF(MSOP) | LINEAR TECHNOLOGY CORPORATION | LTC4307CMS8#TRPBF | 1 | U1 |  |
| IC(22P)MP5022CGQV-Z(QFN) | Monolithic Power Systems, Inc (MPS International Ltd.) | MP5022CGQV-Z | 1 | U38 |  |
| IC CTRL(21P)MPQ8633AGLE-C807-Z(QFN) | Monolithic Power Systems, Inc (MPS International Ltd.) | MPQ8633AGLE-C807-Z | 1 | PU5 |  |
| IC(14P) PCA9543AD(SO14) | PHILIPS LTD,. | PCA9543AD | 1 | U18 |  |
| IC(24P) PCA9555PW(TSSOP)EP | PHILIPS LTD,. | PCA9555PW | 2 | U8,U39 |  |
| IC(5P) 74LVC1G125GV (SOT753) | PHILIPS LTD,. | 74LVC1G125GV | 1 | U21 |  |
| IC OTHER(5P) 74LVC1G08W5-7(SOT25) | DIODES TAIWAN CO.,LTD. | 74LVC1G08W5-7 | 2 | U33,U40 |  |
| IC OTHER(5P) 74LVC1G08W5-7(SOT25) | DIODES TAIWAN CO.,LTD. | 74LVC1G08W5-7 | 2 | U34,U35 |  |
| IC OTHER(5P)74LVC1G07SE-7(SOT353) | DIODES TAIWAN CO.,LTD. | 74LVC1G07SE-7 | 4 | U42,U43,U44,U45 |  |
| TRANS SMD METR3904-G(40V,200MA,0.225W) | Matsuki Precision Ceramic Co., Ltd.Matsuki Polymer Technology Co., Ltd. | METR3904-G | 2 | PQ17,PQ18 |  |
| TRANS SMD MMBT3904-7-F(40V,200MA,8W) | DIODES TAIWAN CO.,LTD. | MMBT3904-7-F | 2 | PQ37,PQ44 |  |
| TRANS MOSFET DMN53D0L-7(50V,0.5A,0.5W) | DIODES TAIWAN CO.,LTD. | DMN53D0L-7 | 7 | U22,U23,U24,U25,U26,U36,U37 |  |
| TRANMOS 2N7002KW SOT323(60V, 115MA,0.2W) | PAN JIT INTERNATIONAL INC. | 2N7002KW | 2 | PU3,PU4 |  |
| TRANS MOS PSMN3R7-100BSE(100V,120A,405W) | Nexperia B.V. | PSMN3R7-100BSE | 14 | PQ6,PQ15,PQ16,PQ32,PQ33,PQ34,PQ35,PQ36,PQ38,PQ39,PQ40,PQ41,PQ42,PQ43 |  |
| DIODE SMD B340A-13-F(40V,3A)SCHOTTKY | DIODES TAIWAN CO.,LTD. | B340A-13-F | 1 | D5 |  |
| DIODE SMD B380-13-F(80V,100A,SCHOTTKY) | DIODES TAIWAN CO.,LTD. | B380-13-F | 2 | PD8,PD10 |  |
| DIODE SMD 5.0SMDJ60A(60V,51.70A) | LITTELFUSE INC. | 5.0SMDJ60A | 4 | PD7,PD9,PD11,PD12 |  |
| DIODE TVS SMBJ14A(14V,25.9A,600W) | LITTELFUSE INC. | SMBJ14A | 1 | D4 |  |
| LED SMD(2P) BLUE(LTST-C281TBKT-5A) | LITEON ELECTRONIC CO., LTD. | LTST-C281TBKT-5A | 3 | D1,D2,D6 |  |
| CAP OSCON SMD 220U 6.3V(20%,5*5.8)NPN | NIPPON CHEMI-CON | APXF6R3ARA221ME611 | 1 | PC137 |  |
| CAP OSCON SMD 270U 16V(20%,6.3*7.7)NPN | NIPPON CHEMI-CON | APXJ160ARA271MF80J | 1 | PC138 |  |
| CAP ELEC DIP 1000UF 80V(+20%,18*25) | NIPPON CHEMI-CON | EKZN800ETD102MM251 | 20 | PC28,PC29,PC30,PC31,PC32,PC33,PC34,PC35,PC36,PC37,PC38,PC39,PC40,PC41,PC42,PC43,PC44,PC45,PC46,PC47 |  |
| CAP CHIP 56P 50V(+5%.NPO.0402) | MURATA ERIE N.A. INC TAIWAN BRANCH Okayama Murata Mfg.Co.,Ltd.Wakura Murata Mfg. Co., Ltd. (Peregrine Semiconductor Corp) | GRM1555C1H560J | 1 | PC54 |  |
| CAP CHIP 560P 50V(+10%,X7R,0402) | MURATA ERIE N.A. INC TAIWAN BRANCH Okayama Murata Mfg.Co.,Ltd.Wakura Murata Mfg. Co., Ltd. (Peregrine Semiconductor Corp) | GRM155R71H561K | 1 | C101 |  |
| CAP CHIP 2200P 50V(+10%.X7R.0402) | WALSIN TECHNOLOGY CORPORATION | 0402B222K500CT | 2 | PC12,PC615 |  |
| CAP CHIP 0.01U 50V(+10%,X7R,0402) | MURATA ERIE N.A. INC TAIWAN BRANCH Okayama Murata Mfg.Co.,Ltd.Wakura Murata Mfg. Co., Ltd. (Peregrine Semiconductor Corp) | WBM155R71H103K | 2 | PC590,PC610 | HSC1_BOM2 |
| CAP CHIP 0.01U 100V(+10%.X7R.0603) | MURATA ERIE N.A. INC TAIWAN BRANCH Okayama Murata Mfg.Co.,Ltd.Wakura Murata Mfg. Co., Ltd. (Peregrine Semiconductor Corp) | GRM188R72A103K | 4 | C69,C88,C90,C92 |  |
| CAP CHIP 0.047U 25V(+10% X7R 0402) | MURATA ERIE N.A. INC TAIWAN BRANCH Okayama Murata Mfg.Co.,Ltd.Wakura Murata Mfg. Co., Ltd. (Peregrine Semiconductor Corp) | GRM155R71E473K | 1 | C99 |  |
| CAP CHIP 0.1U 16V(10%.X7R.0402) | MURATA ERIE N.A. INC TAIWAN BRANCH Okayama Murata Mfg.Co.,Ltd.Wakura Murata Mfg. Co., Ltd. (Peregrine Semiconductor Corp) | WBM155R71C104K | 6 | C1,C3,C8,C91,C93,C102 |  |
| CAP CHIP 0.1U 16V(10%.X7R.0402) | MURATA ERIE N.A. INC TAIWAN BRANCH Okayama Murata Mfg.Co.,Ltd.Wakura Murata Mfg. Co., Ltd. (Peregrine Semiconductor Corp) | WBM155R71C104K | 8 | C9,C26,C89,C103,C104,C105,C106,C107 |  |
| CAP CHIP 0.1U 25V(+10%,X7R,0402) | YAGEO CORPORATION | CC0402KRX7R8BB104 | 1 | C96 |  |
| CAP CHIP 0.1U 25V(+10%,X7R,0402) | YAGEO CORPORATION | CC0402KRX7R8BB104 | 4 | PC9,PC586,PC606,PC612 | HSC1_BOM2 |
| CAP CHIP 0.1U 25V(+10%,X7R,0402) | YAGEO CORPORATION | CC0402KRX7R8BB104 | 7 | PC51,PC52,PC53,PC575,PC576,PC577,PC578 |  |
| CAP CHIP 100NF 50V(+10%,X7R,0402) | YAGEO CORPORATION | CC0402KRX7R9BB104 | 1 | C100 |  |
| CAP CHIP 0.1U 100V(+10%.X7R.1206)H1.25 | WALSIN TECHNOLOGY CORPORATION | 1206B104K101CT | 2 | PC587,PC607 | HSC1_BOM2 |
| CAP CHIP 0.15U 100V(+10%,X7R,0805) | WALSIN TECHNOLOGY CORPORATION | 0805B154K101CT | 2 | PC13,PC616 | HSC1_BOM2 |
| CAP CHIP 0.22U 25V(10%,X7R,0402) | TAIYO YUDEN CO.,LTD | TMK105B7224KV-FR | 1 | C97 |  |
| CAP CHIP 0.47U 16V (+-10%,X7R,0603) | KEMET ELECTRONICS CORPORATION | C0603C474K4RAC | 2 | PC11,PC614 | HSC1_BOM2 |
| CAP CHIP 1U 25V(+10%.X7R.0603)MUR | MURATA ERIE N.A. INC TAIWAN BRANCH Okayama Murata Mfg.Co.,Ltd.Wakura Murata Mfg. Co., Ltd. (Peregrine Semiconductor Corp) | GRM188R71E105K | 2 | PC591,PC611 | HSC1_BOM2 |
| CAP CHIP 1UF 25V(+10%,X6S,0402) | MURATA ERIE N.A. INC TAIWAN BRANCH Okayama Murata Mfg.Co.,Ltd.Wakura Murata Mfg. Co., Ltd. (Peregrine Semiconductor Corp) | GRM155C81E105K | 2 | PC60,C94 |  |
| CAP CHIP 1UF 25V(+10%,X6S,0402) | MURATA ERIE N.A. INC TAIWAN BRANCH Okayama Murata Mfg.Co.,Ltd.Wakura Murata Mfg. Co., Ltd. (Peregrine Semiconductor Corp) | GRM155C81E105K | 2 | PC10,PC613 | HSC1_BOM2 |
| CAP CHIP 1UF 25V(+10%,X6S,0402) | MURATA ERIE N.A. INC TAIWAN BRANCH Okayama Murata Mfg.Co.,Ltd.Wakura Murata Mfg. Co., Ltd. (Peregrine Semiconductor Corp) | GRM155C81E105K | 1 | PC55 |  |
| CAP CHIP 1U 100V(10%.1206.X7R)MUR | MURATA ERIE N.A. INC TAIWAN BRANCH Okayama Murata Mfg.Co.,Ltd.Wakura Murata Mfg. Co., Ltd. (Peregrine Semiconductor Corp) | GRF31CR72A105K | 2 | PC588,PC608 | HSC1_BOM2 |
| CAP CHIP 2.2UF 16V(20%,X7R,0603) | TAIYO YUDEN CO.,LTD | EMK107BB7225MA-T | 1 | C98 |  |
| CAP CHIP 10U 25V(+10%,X6S,0805)MUR | MURATA ERIE N.A. INC TAIWAN BRANCH Okayama Murata Mfg.Co.,Ltd.Wakura Murata Mfg. Co., Ltd. (Peregrine Semiconductor Corp) | GRM21BC81E106K | 1 | C95 |  |
| CAP CHIP 22U 6.3V(+20%,X6S,0805)MUR | MURATA ERIE N.A. INC TAIWAN BRANCH Okayama Murata Mfg.Co.,Ltd.Wakura Murata Mfg. Co., Ltd. (Peregrine Semiconductor Corp) | GRM21BC80J226M | 3 | PC48,PC49,PC50 |  |
| CAP CHIP 22U 16V(+20%,X6S,0805) | MURATA ERIE N.A. INC TAIWAN BRANCH Okayama Murata Mfg.Co.,Ltd.Wakura Murata Mfg. Co., Ltd. (Peregrine Semiconductor Corp) | GRM21BC81C226M | 6 | PC56,PC57,PC58,PC59,PC617,PC618 |  |
| RES CHIP 0 1/16W +5%(0402)EF | WALSIN TECHNOLOGY CORPORATION | WR04X000PTR | 16 | R84,R85,R86,R87,PR97,PR99,PR102,PR103,PR105,R394,R413,PR473,R5896,R5900,R5915,R5930 |  |
| RES CHIP 0 1/16W +5%(0402)EF | WALSIN TECHNOLOGY CORPORATION | WR04X000PTR | 4 | PR6967,PR6968,PR6995,PR6996 | HSC1_BOM2 |
| RES CHIP 0 1/16W +5%(0402)EF | WALSIN TECHNOLOGY CORPORATION | WR04X000PTR | 16 | R3,R13,R14,R71,R72,R73,R74,R75,R76,R77,R78,R5898,R5927,R5928,R5940,R5941 |  |
| RES CHIP 0 1/16W +5%(0402)EF | WALSIN TECHNOLOGY CORPORATION | WR04X000PTR | 16 | R81,R144,R145,R151,R372,R373,R5860,R5861,R5866,R5867,R5882,R5883,R5886,R5888,R5891,R5895 | HSC1_BOM2 |
| RES CHIP 10 1/10W +1%(0603)EF | WALSIN TECHNOLOGY CORPORATION | WR06X10R0FTR | 12 | PR16,PR474,PR475,PR476,PR477,PR478,PR6970,PR6971,PR6972,PR6973,PR6974,PR6975 |  |
| RES CHIP 10 1/10W +1%(0603)EF | WALSIN TECHNOLOGY CORPORATION | WR06X10R0FTR | 8 | PR6958,PR6959,PR6960,PR6961,PR6985,PR6986,PR6990,PR6991 | HSC1_BOM2 |
| RES CHIP 33 1/16W +1%(0402)EF | WALSIN TECHNOLOGY CORPORATION | WR04X33R0FTR | 13 | R4,R5,R11,R12,R19,R20,R49,R50,R62,R63,R389,R5932,R5933 |  |
| RES CHIP 49.9 1/10W +1%(0603)EF | YAGEO CORPORATION | RC0603FR-0749R9P | 1 | R5920 |  |
| RES CHIP 75 1/16W +1%(0402)EF | WALSIN TECHNOLOGY CORPORATION | WR04X75R0FTR | 1 | R5929 |  |
| RES CHIP 1 2W +1%(2512)EF | WALSIN TECHNOLOGY CORPORATION | WF25P1R00FTR | 4 | PR100,PR101,PR106,PR107 |  |
| RES CHIP 100 1/16W +1%(0402)EF | WALSIN TECHNOLOGY CORPORATION | WR04X1000FTR | 1 | R24 |  |
| RES CHIP 100 1/2W+5%(1206)SR | RALEC ELECTRONIC CO. | RTG06101JTP | 2 | PR5,PR7020 | HSC1_BOM2 |
| RES CHIP 220 1/16W +5%(0402)EF | WALSIN TECHNOLOGY CORPORATION | WR04X221 JTR | 2 | R64,R65 |  |
| RES CHIP 301 1/16W +1%(0402)EF | WALSIN TECHNOLOGY CORPORATION | WR04X3010FTR | 1 | R382 |  |
| RES CHIP 1K 1/16W +1%(0402)EF | WALSIN TECHNOLOGY CORPORATION | WR04X1001FTR | 1 | R52 |  |
| RES CHIP 1K 1/16W +1%(0402)EF | WALSIN TECHNOLOGY CORPORATION | WR04X1001FTR | 11 | R53,R54,R100,R101,R133,R135,R137,R5917,R5934,R5936,R5938 |  |
| RES CHIP 1K 1/16W +1%(0402)EF | WALSIN TECHNOLOGY CORPORATION | WR04X1001FTR | 1 | R96 | HSC1_BOM2 |
| RES CHIP 1K 1/4W +5%(1206)EF | RALEC ELECTRONIC CO. | FTT06102JTP | 10 | R38,R39,R40,R41,R42,R43,R44,R45,R46,R47 |  |
| RES CHIP 1.65K 1/16W +1%(0402)EF | WALSIN TECHNOLOGY CORPORATION | WR04X1651FTR | 2 | PR482,PR6979 |  |
| RES CHIP 2.2 1/16W +1%(0402)EF | WALSIN TECHNOLOGY CORPORATION | WR04W2R20FTR | 1 | PR111 |  |
| RES CHIP 2.21K 1/16W +1%(0402)EF | WALSIN TECHNOLOGY CORPORATION | WR04X2211FTR | 2 | PR483,PR6980 |  |
| RES CHIP 2.26K 1/16W +1%(0402)EF | WALSIN TECHNOLOGY CORPORATION | WR04X2261FTR | 2 | PR6931,PR7021 | HSC1_BOM2 |
| RES CHIP 2.43K 1/16W +1%(0402)EF | WALSIN TECHNOLOGY CORPORATION | WR04X2431FTR | 2 | PR6932,PR7025 | HSC1_BOM2 |
| RES CHIP 3.83K 1/16W +1%(0402)EF | RALEC ELECTRONIC CO. | FTT023831FTH | 2 | PR20,PR7028 |  |
| RES CHIP 4.7K 1/16W +5%(0402)EF | WALSIN TECHNOLOGY CORPORATION | WR04X472 JTR | 10 | R15,R16,R48,R61,R386,R5931,R5942,R5943,R5944,R5945 |  |
| RES CHIP 4.7K 1/16W +5%(0402)EF | WALSIN TECHNOLOGY CORPORATION | WR04X472 JTR | 3 | R23,R5913,R5914 |  |
| RES CHIP 4.7K 1/16W +5%(0402)EF | WALSIN TECHNOLOGY CORPORATION | WR04X472 JTR | 2 | R150,R5887 | HSC1_BOM2 |
| RES CHIP 4.87K 1/16W +1%(0402)EF | WALSIN TECHNOLOGY CORPORATION | WR04X4871FTR | 1 | PR113 |  |
| RES CHIP 8.45K 1/16W +1%( 0402)EF | WALSIN TECHNOLOGY CORPORATION | WR04X8451FTR | 2 | R5903,R5907 |  |
| RES CHIP 10K 1/16W +1%(0402)EF | WALSIN TECHNOLOGY CORPORATION | WR04X1002FTR | 2 | PR93,PR7031 | HSC1_BOM2 |
| RES CHIP 10K 1/16W +1%(0402)EF | WALSIN TECHNOLOGY CORPORATION | WR04X1002FTR | 1 | PR110 |  |
| RES CHIP 10K 1/16W +1%(0402)EF | WALSIN TECHNOLOGY CORPORATION | WR04X1002FTR | 9 | R1,R2,R328,R329,R330,R331,R5916,R5922,R5925 |  |
| RES CHIP 10K 1/16W +5%(0402)EF | WALSIN TECHNOLOGY CORPORATION | WR04X103 JTR | 3 | R58,R5911,R5912 |  |
| RES CHIP 11.5K 1/16W +1%(0402)EF | WALSIN TECHNOLOGY CORPORATION | WR04X1152FTR | 4 | R149,R5881,R5904,R5908 |  |
| RES CHIP 11.5K 1/16W +1%(0402)EF | WALSIN TECHNOLOGY CORPORATION | WR04X1152FTR | 2 | R399,R5897 |  |
| RES CHIP 12.4K 1/16W +1%(0402)EF | YAGEO CORPORATION | RC0402FR-0712K4P | 1 | PR114 |  |
| RES CHIP 16.9K 1/16W +1%(0402)EF | YAGEO CORPORATION | RC0402FR-0716K9P | 2 | PR31,PR7032 | HSC1_BOM2 |
| RES CHIP 20K 1/16W +1%(0402)EF | WALSIN TECHNOLOGY CORPORATION | WR04X2002FTR | 1 | R5924 |  |
| RES CHIP 20K 1/8W +1%(0805)EF | WALSIN TECHNOLOGY CORPORATION | WR08X2002FTR | 2 | PR32,PR7033 | HSC1_BOM2 |
| RES CHIP 20K 1/4W +1%(1206)EF | RALEC ELECTRONIC CO. | FTT062002FTP | 2 | PR98,PR104 |  |
| RES CHIP 37.4K 1/16W +1%(0402)EF | WALSIN TECHNOLOGY CORPORATION | WR04X3742FTR | 2 | R155,R385 |  |
| RES CHIP 46.4K 1/16W +1%(0402)EF | WALSIN TECHNOLOGY CORPORATION | WR04X4642FTR | 1 | R5926 |  |
| RES CHIP 53.6K 1/16W +1%(0402)EF | WALSIN TECHNOLOGY CORPORATION | WR04X5362FTR | 2 | PR21,PR7030 |  |
| RES CHIP 56K 1/16W +1%(0402)EF | WALSIN TECHNOLOGY CORPORATION | WR04X5602FTR | 1 | PR112 |  |
| RES CHIP 95.3K 1/8W +1%(0805)EF | WALSIN TECHNOLOGY CORPORATION | WR08X9532FTR | 4 | PR4,PR17,PR7019,PR7022 | HSC1_BOM2 |
| RES CHIP 95.3K 1/8W +1%(0805)EF | WALSIN TECHNOLOGY CORPORATION | WR08X9532FTR | 4 | PR480,PR481,PR6977,PR6978 |  |
| RES CHIP 95.3K 1/8W +1%(0805)EF | WALSIN TECHNOLOGY CORPORATION | WR08X9532FTR | 2 | R5901,R5905 |  |
| RES CHIP 97.6K 1/16W +1%(0402)EF | WALSIN TECHNOLOGY CORPORATION | WR04X9762FTR | 2 | PR6933,PR7026 |  |
| RES CHIP 100K 1/16W +1%(0402)EF | WALSIN TECHNOLOGY CORPORATION | WR04X1003FTR | 4 | PR35,PR6934,PR7027,PR7034 | HSC1_BOM2 |
| RES CHIP 100K 1/16W +5%(0402)EF | WALSIN TECHNOLOGY CORPORATION | WR04X104 JTR | 3 | R186,R383,R387 |  |
| RES CHIP 120K 1/16W +1%(0402)EF | YAGEO CORPORATION | RC0402FR-07120KP | 1 | R5919 |  |
| RES CHIP 130K 1/16W +1%(0402)EF | WALSIN TECHNOLOGY CORPORATION | WR04X1303FTR | 1 | R5923 |  |
| RES CHIP 174K 1/8W +1%(0805)EF | EVER OHMS TECHNOLOGY CO., LTD. | CRG0805F174KP05Z | 4 | R148,R5880,R5902,R5906 |  |
| RES CHIP 174K 1/8W +1%(0805)EF | EVER OHMS TECHNOLOGY CO., LTD. | CRG0805F174KP05Z | 2 | R398,R5893 |  |
| RES CHIP 390K 1/16W +1%(0402)EF | WALSIN TECHNOLOGY CORPORATION | WR04X3903FTR | 2 | PR37,PR7036 | HSC1_BOM2 |
| RES CHIP 499K 1/8W+1%(0805)EF | WALSIN TECHNOLOGY CORPORATION | WR08X4993FTR | 2 | R154,R384 |  |
| RES CHIP 2.05M 1/8W +1%(0805)EF | EVER OHMS TECHNOLOGY CO., LTD. | CRG0805F2M05P05Z | 2 | PR19,PR7024 | HSC1_BOM2 |
| IND SMD 2.2UH 20% 32A(PCMC135T-2R2MF) | CYNTEC CO., LTD. | PCMC135T-2R2MF | 1 | PL2 |  |
| IND SMD 100NH 20% 16A(HCBS4545-101) | DELTA ELECTRONIC IND. CO., LTD. DELTA ELECTRONICS COMPONENT(WUJIANG)LTD | HCBS4545-101 | 1 | PL1 |  |
| CONN DIP HEADER 1P MS(H32) | AMPHENOL EAST ASIA LIMITED (Amphenol-TCS) (Shanghai Amphenol Airwave Communication Electronics Co.,L......(Skip) | 10037910-101LF | 2 | J15,J16 |  |
| CONN DIP HEADER 3P 1R MS(P2.54,H8.38) | (FOXCONN) HON HAI PRECISION INDUSTRY KANG ZHUN PRESION TOOLING(KUN SHAN)CO.,LTD FuYu Precision Component(KunShan)Co.,Ltd.FuRui Precision Components(KunShan)Co.,LtiKang Zhun Precision Tooling(KunShan)Co.,Ltd, FuHon Precision Components(KunShan)Co., | HBB1037-L300D-8H | 3 | JP3,JP5,JP6 |  |
| CONN DIP HEADER 36P 4R MS(P2.54,H12.7) | AMPHENOL EAST ASIA LIMITED (Amphenol-TCS) (Shanghai Amphenol Airwave Communication Electronics Co.,L......(Skip) | 10106267-4001501LF | 2 | J6,J7 |  |
| CONN DIP HOUSING 12P 2R FS(P1.27,H15.49) | AMPHENOL EAST ASIA LIMITED (Amphenol-TCS) (Shanghai Amphenol Airwave Communication Electronics Co.,L......(Skip) | 10121505-0004082LF | 2 | J8,J9 |  |
| CONN DIP HOUSING 24P 6R FR(P2,H10.5) | AMPHENOL EAST ASIA LIMITED (Amphenol-TCS) (Shanghai Amphenol Airwave Communication Electronics Co.,L......(Skip) | 10134701-5544P00LF | 2 | J1,J3 |  |
| CONN DIP HOUSING 32P 2R FS(P1.27,H19.49) | AMPHENOL EAST ASIA LIMITED (Amphenol-TCS) (Shanghai Amphenol Airwave Communication Electronics Co.,L......(Skip) | 10167141-001LF | 1 | J11 |  |
| CONN DIP HOUSING 36P 4R FR(P2,H19.8) | AMPHENOL EAST ASIA LIMITED (Amphenol-TCS) (Shanghai Amphenol Airwave Communication Electronics Co.,L......(Skip) | 10141042-200A003LF | 2 | JP1,JP2 |  |
| CONN DIP HS 36P 6R FR(P2.0,H10.5)HV | AMPHENOL EAST ASIA LIMITED (Amphenol-TCS) (Shanghai Amphenol Airwave Communication Electronics Co.,L......(Skip) | 10146092-555444PLF | 2 | J2,J4 |  |
| FUSE SMD 20A/125V(FAST,UL/CSA) | LITTELFUSE INC. | 0456020.ER | 2 | FS5,FS6 |  |
| RES CHIP 0.0003 4W +1%(2725) | RALEC ELECTRONIC CO. | LR2725-24R0003F1 | 4 | PR315,PR479,PR6976,PR6989 |  |
| HANDLE PDB F0T(FBF0T140,R3A)FVT | Fivetech Technology Inc. | FBF0T14001 | 2 | H21_22,H23_24 |  |
| SCREW #6-32UNC*6-B(NYLOK)IRON | SCREW TECH INDUDTRY CO., LTD. | MU06060BCI2 | 4 | H21,H22,H23,H24 |  |
| SMT THUMBSCREW H18.5 F0G(FBF0G001,3A)FVT | Fivetech Technology Inc. | FBF0G01001 | 2 | H19,H20 |  |
| SCREW M3*12-H(NI,NYLOK,D5.5,T2.6)STEEL | SCREW TECH INDUDTRY CO., LTD. | SCREW M3*12-H(NI,NYLOK,D5.5,T2.6)STEEL | 4 | J6_SCREW_1,J6_SCREW_2,J7_SCREW_1,J7_SCREW_2 |  |
| NUT PDB F0T(MBF0T001,3A) STEEL | SCREW TECH INDUDTRY CO., LTD. | NHMM5X4-2 | 2 | J15_NUT,J16_NUT |  |
| LABEL SERIAL PL S6I(HCS6I019,3A) | HWAKUAN LABEL & PRINTING CO.,LTD | HCS6I01901 | 1 | PN_LABEL |  |
| PLBL LBL HIGHTEMP17X12 S2L(HCS2L067,R3C) | HWAKUAN LABEL & PRINTING CO.,LTD | HCS2L06701 | 1 | STAGE_LABEL |  |
| MB LABEL  (HCT70001,REV3A) | HWAKUAN LABEL & PRINTING CO.,LTD | HCT70001 | 1 | REWORK_LABEL |  |
| NUT SMD M3 H3.53 T6U(MBT6U008,3A)STL | SCREW TECH INDUDTRY CO., LTD. | MBT6U00801 | 4 | H32,H33,H34,H35 |  |
